# S9S_MB_2U (Grand Teton) — schematic netlist excerpt (pin names and nets, part order shuffled) for the footprints in the layout excerpt that follows; sources: Cadence DE-HDL packaged netlist, KiCad conversion of 03242023_DA0F0TMBIJ0_F0T_Motherboard_J_brd_V01_OCP.brd

J2  SCONN288_ADR50017P087CC  SCONN288_ADR50017-P087CC IO  pkg DDR288S_1-1VXB  page 83
  VIN_BULK0  = P12V_S3_AUX_CPU0_NVDIMM
  RFU0  = TP_CHA_CPU0_DIMM2_FRU_0
  VIN_MGMT  = P3V3_AUX
  HSCL  = I3C_SPD_DDRABCD_CPU0_LVC1_SCL_1
  HSDA  = I3C_SPD_DDRABCD_CPU0_LVC1_SDA
  VSS0  = GND
  DQ0_A  = M_A_CPU0_SA_DQ<0>
  VSS1  = GND
  DQ1_A  = M_A_CPU0_SA_DQ<1>
  VSS2  = GND
  DQS0_A_T  = M_A_CPU0_SA_DQS_DP<0>
  DQS0_A_C  = M_A_CPU0_SA_DQS_DN<0>
  VSS3  = GND
  DQ4_A  = M_A_CPU0_SA_DQ<4>
  VSS4  = GND
  DQ5_A  = M_A_CPU0_SA_DQ<5>
  VSS5  = GND
  DQ8_A  = M_A_CPU0_SA_DQ<8>
  VSS6  = GND
  DQ9_A  = M_A_CPU0_SA_DQ<9>
  VSS7  = GND
  DQS1_A_T  = M_A_CPU0_SA_DQS_DP<1>
  DQS1_A_C  = M_A_CPU0_SA_DQS_DN<1>
  VSS8  = GND
  DQ12_A  = M_A_CPU0_SA_DQ<12>
  VSS9  = GND
  DQ13_A  = M_A_CPU0_SA_DQ<13>
  VSS10  = GND
  DQ16_A  = M_A_CPU0_SA_DQ<16>
  VSS11  = GND
  DQ17_A  = M_A_CPU0_SA_DQ<17>
  VSS12  = GND
  DQS2_A_T  = M_A_CPU0_SA_DQS_DP<2>
  DQS2_A_C  = M_A_CPU0_SA_DQS_DN<2>
  VSS13  = GND
  DQ20_A  = M_A_CPU0_SA_DQ<20>
  VSS14  = GND
  DQ21_A  = M_A_CPU0_SA_DQ<21>
  VSS15  = GND
  DQ24_A  = M_A_CPU0_SA_DQ<24>
  VSS16  = GND
  DQ25_A  = M_A_CPU0_SA_DQ<25>
  VSS17  = GND
  DQS3_A_T  = M_A_CPU0_SA_DQS_DP<3>
  DQS3_A_C  = M_A_CPU0_SA_DQS_DN<3>
  VSS18  = GND
  DQ28_A  = M_A_CPU0_SA_DQ<28>
  VSS19  = GND
  DQ29_A  = M_A_CPU0_SA_DQ<29>
  VSS20  = GND
  CB0_A  = M_A_CPU0_SA_CB<0>
  VSS21  = GND
  CB1_A  = M_A_CPU0_SA_CB<1>
  VSS22  = GND
  DQS4_A_T  = M_A_CPU0_SA_DQS_DP<4>
  DQS4_A_C  = M_A_CPU0_SA_DQS_DN<4>
  VSS23  = GND
  CB4_A  = M_A_CPU0_SA_CB<4>
  VSS24  = GND
  CB5_A  = M_A_CPU0_SA_CB<5>
  VSS25  = GND
  ALERT_N  = M_A_CPU0_ALERT_N
  VSS26  = GND
  CS0_A_N  = M_A_CPU0_SA_CS_N<2>
  VSS27  = GND
  CA0_A  = M_A_CPU0_SA_CA<0>
  VSS28  = GND
  CA2_A  = M_A_CPU0_SA_CA<2>
  VSS29  = GND
  CA4_A  = M_A_CPU0_SA_CA<4>
  VSS30  = GND
  CA6_A  = M_A_CPU0_SA_CA<6>
  VSS31  = GND
  PAR_A  = M_A_CPU0_SA_PAR
  VSS32  = GND
  CA0_B  = M_A_CPU0_SB_CA<0>
  VSS33  = GND
  CA2_B  = M_A_CPU0_SB_CA<2>
  VSS34  = GND
  CA4_B  = M_A_CPU0_SB_CA<4>
  VSS35  = GND
  CA6_B  = M_A_CPU0_SB_CA<6>
  VSS36  = GND
  CS0_B_N  = M_A_CPU0_SB_CS_N<2>
  VSS37  = GND
  \lbd||rsp_a_n\  = M_A_CPU0_SA_RSP<1>
  \lbs||rsp_b_n\  = M_A_CPU0_SB_RSP<1>
  VSS38  = GND
  CB4_B  = M_A_CPU0_SB_CB<4>
  VSS39  = GND
  CB5_B  = M_A_CPU0_SB_CB<5>
  VSS40  = GND
  \dqs9_b_t||tdqs9_b_t||dbi4_b_n\  = M_A_CPU0_SB_DQS_DP<9>
  \dqs9_b_c||tdqs9_b_c\  = M_A_CPU0_SB_DQS_DN<9>
  VSS41  = GND
  CB0_B  = M_A_CPU0_SB_CB<0>
  VSS42  = GND
  CB1_B  = M_A_CPU0_SB_CB<1>
  VSS43  = GND
  DQ0_B  = M_A_CPU0_SB_DQ<0>
  VSS44  = GND
  DQ1_B  = M_A_CPU0_SB_DQ<1>
  VSS45  = GND
  DQS0_B_T  = M_A_CPU0_SB_DQS_DP<0>
  DQS0_B_C  = M_A_CPU0_SB_DQS_DN<0>
  VSS46  = GND
  DQ4_B  = M_A_CPU0_SB_DQ<4>
  VSS47  = GND
  DQ5_B  = M_A_CPU0_SB_DQ<5>
  VSS48  = GND
  DQ8_B  = M_A_CPU0_SB_DQ<8>
  VSS49  = GND
  DQ9_B  = M_A_CPU0_SB_DQ<9>
  VSS50  = GND
  DQS1_B_T  = M_A_CPU0_SB_DQS_DP<1>
  DQS1_B_C  = M_A_CPU0_SB_DQS_DN<1>
  VSS51  = GND
  DQ12_B  = M_A_CPU0_SB_DQ<12>
  VSS52  = GND
  DQ13_B  = M_A_CPU0_SB_DQ<13>
  VSS53  = GND
  DQ16_B  = M_A_CPU0_SB_DQ<16>
  VSS54  = GND
  DQ17_B  = M_A_CPU0_SB_DQ<17>
  VSS55  = GND
  DQS2_B_T  = M_A_CPU0_SB_DQS_DP<2>
  DQS2_B_C  = M_A_CPU0_SB_DQS_DN<2>
  VSS56  = GND
  DQ20_B  = M_A_CPU0_SB_DQ<20>
  VSS57  = GND
  DQ21_B  = M_A_CPU0_SB_DQ<21>
  VSS58  = GND
  DQ24_B  = M_A_CPU0_SB_DQ<24>
  VSS59  = GND
  DQ25_B  = M_A_CPU0_SB_DQ<25>
  VSS60  = GND
  DQS3_B_T  = M_A_CPU0_SB_DQS_DP<3>
  DQS3_B_C  = M_A_CPU0_SB_DQS_DN<3>
  VSS61  = GND
  DQ28_B  = M_A_CPU0_SB_DQ<28>
  VSS62  = GND
  DQ29_B  = M_A_CPU0_SB_DQ<29>
  VSS63  = GND
  RFU1  = TP_CHA_CPU0_DIMM2_FRU_1
  VIN_BULK1  = P12V_S3_AUX_CPU0_NVDIMM
  VIN_BULK2  = P12V_S3_AUX_CPU0_NVDIMM
  \pwr_good||fail_n\  = PWRGD_CHA_CPU0_DIMM2
  HSA  = PD_CHA_CPU0_DIMM2_SAA
  RFU2  = TP_CHA_CPU0_DIMM2_FRU_2
  RFU3  = TP_CHA_CPU0_DIMM2_FRU_3
  VSS64  = GND
  DQ2_A  = M_A_CPU0_SA_DQ<2>
  VSS65  = GND
  DQ3_A  = M_A_CPU0_SA_DQ<3>
  VSS66  = GND
  \dqs5_a_c||tdqs5_a_c||dqs5_a_t||tdqs5_a_t\  = M_A_CPU0_SA_DQS_DN<5>
  \dqs5_a_t||tdqs5_a_t\  = M_A_CPU0_SA_DQS_DP<5>
  VSS67  = GND
  DQ6_A  = M_A_CPU0_SA_DQ<6>
  VSS68  = GND
  DQ7_A  = M_A_CPU0_SA_DQ<7>
  VSS69  = GND
  DQ10_A  = M_A_CPU0_SA_DQ<10>
  VSS70  = GND
  DQ11_A  = M_A_CPU0_SA_DQ<11>
  VSS71  = GND
  \dqs6_a_c||tdqs6_a_c||dqs6_a_t||tdqs6_a_t\  = M_A_CPU0_SA_DQS_DN<6>
  \dqs6_a_t||tdqs6_a_t\  = M_A_CPU0_SA_DQS_DP<6>
  VSS72  = GND
  DQ14_A  = M_A_CPU0_SA_DQ<14>
  VSS73  = GND
  DQ15_A  = M_A_CPU0_SA_DQ<15>
  VSS74  = GND
  DQ18_A  = M_A_CPU0_SA_DQ<18>
  VSS75  = GND
  DQ19_A  = M_A_CPU0_SA_DQ<19>
  VSS76  = GND
  \dqs7_a_c||tdqs7_a_c\  = M_A_CPU0_SA_DQS_DN<7>
  \dqs7_a_t||tdqs7_a_t\  = M_A_CPU0_SA_DQS_DP<7>
  VSS77  = GND
  DQ22_A  = M_A_CPU0_SA_DQ<22>
  VSS78  = GND
  DQ23_A  = M_A_CPU0_SA_DQ<23>
  VSS79  = GND
  DQ26_A  = M_A_CPU0_SA_DQ<26>
  VSS80  = GND
  DQ27_A  = M_A_CPU0_SA_DQ<27>
  VSS81  = GND
  \dqs8_a_c||tdqs8_a_c\  = M_A_CPU0_SA_DQS_DN<8>
  \dqs8_a_t||tdqs8_a_t\  = M_A_CPU0_SA_DQS_DP<8>
  VSS82  = GND
  DQ30_A  = M_A_CPU0_SA_DQ<30>
  VSS83  = GND
  DQ31_A  = M_A_CPU0_SA_DQ<31>
  VSS84  = GND
  CB2_A  = M_A_CPU0_SA_CB<2>
  VSS85  = GND
  CB3_A  = M_A_CPU0_SA_CB<3>
  VSS86  = GND
  \dqs9_a_c||tdqs9_a_c\  = M_A_CPU0_SA_DQS_DN<9>
  \dqs9_a_t||tdqs9_a_t\  = M_A_CPU0_SA_DQS_DP<9>
  VSS87  = GND
  CB6_A  = M_A_CPU0_SA_CB<6>
  VSS88  = GND
  CB7_A  = M_A_CPU0_SA_CB<7>
  VSS89  = GND
  RESET_N  = RST_M_AB_CPU0_FPGA_N
  VSS90  = GND
  CS1_A_N  = M_A_CPU0_SA_CS_N<3>
  VSS91  = GND
  CA1_A  = M_A_CPU0_SA_CA<1>
  VSS92  = GND
  CA3_A  = M_A_CPU0_SA_CA<3>
  VSS93  = GND
  CA5_A  = M_A_CPU0_SA_CA<5>
  VSS94  = GND
  CK_T  = M_A_CPU0_CLK_DP<1>
  CK_C  = M_A_CPU0_CLK_DN<1>
  VSS95  = GND
  RFU4  = TP_CHA_CPU0_DIMM2_FRU_4
  CA1_B  = M_A_CPU0_SB_CA<1>
  VSS96  = GND
  CA3_B  = M_A_CPU0_SB_CA<3>
  VSS97  = GND
  CA5_B  = M_A_CPU0_SB_CA<5>
  VSS98  = GND
  PAR_B  = M_A_CPU0_SB_PAR
  VSS99  = GND
  CS1_B_N  = M_A_CPU0_SB_CS_N<3>
  VSS100  = GND
  RFU5  = TP_CHA_CPU0_DIMM2_FRU_5
  RFU6  = TP_CHA_CPU0_DIMM2_FRU_6
  VSS101  = GND
  CB6_B  = M_A_CPU0_SB_CB<6>
  VSS102  = GND
  CB7_B  = M_A_CPU0_SB_CB<7>
  VSS103  = GND
  DQS4_B_C  = M_A_CPU0_SB_DQS_DN<4>
  DQS4_B_T  = M_A_CPU0_SB_DQS_DP<4>
  VSS104  = GND
  CB2_B  = M_A_CPU0_SB_CB<2>
  VSS105  = GND
  CB3_B  = M_A_CPU0_SB_CB<3>
  VSS106  = GND
  DQ2_B  = M_A_CPU0_SB_DQ<2>
  VSS107  = GND
  DQ3_B  = M_A_CPU0_SB_DQ<3>
  VSS108  = GND
  \dqs5_b_c||tdqs5_b_c\  = M_A_CPU0_SB_DQS_DN<5>
  \dqs5_b_t||tdqs5_b_t\  = M_A_CPU0_SB_DQS_DP<5>
  VSS109  = GND
  DQ6_B  = M_A_CPU0_SB_DQ<6>
  VSS110  = GND
  DQ7_B  = M_A_CPU0_SB_DQ<7>
  VSS111  = GND
  DQ10_B  = M_A_CPU0_SB_DQ<10>
  VSS112  = GND
  DQ11_B  = M_A_CPU0_SB_DQ<11>
  VSS113  = GND
  \dqs6_b_c||tdqs6_b_c\  = M_A_CPU0_SB_DQS_DN<6>
  \dqs6_b_t||tdqs6_b_t\  = M_A_CPU0_SB_DQS_DP<6>
  VSS114  = GND
  DQ14_B  = M_A_CPU0_SB_DQ<14>
  VSS115  = GND
  DQ15_B  = M_A_CPU0_SB_DQ<15>
  VSS116  = GND
  DQ18_B  = M_A_CPU0_SB_DQ<18>
  VSS117  = GND
  DQ19_B  = M_A_CPU0_SB_DQ<19>
  VSS118  = GND
  \dqs7_b_c||tdqs7_b_c\  = M_A_CPU0_SB_DQS_DN<7>
  \dqs7_b_t||tdqs7_b_t\  = M_A_CPU0_SB_DQS_DP<7>
  VSS119  = GND
  DQ22_B  = M_A_CPU0_SB_DQ<22>
  VSS120  = GND
  DQ23_B  = M_A_CPU0_SB_DQ<23>
  VSS121  = GND
  DQ26_B  = M_A_CPU0_SB_DQ<26>
  VSS122  = GND
  DQ27_B  = M_A_CPU0_SB_DQ<27>
  VSS123  = GND
  \dqs8_b_c||tdqs8_b_c\  = M_A_CPU0_SB_DQS_DN<8>
  \dqs8_b_t||tdqs8_b_t\  = M_A_CPU0_SB_DQS_DP<8>
  VSS124  = GND
  DQ30_B  = M_A_CPU0_SB_DQ<30>
  VSS125  = GND
  DQ31_B  = M_A_CPU0_SB_DQ<31>
  VSS126  = GND
  G1  = GND
  G2  = GND
  G3  = GND

(kicad_pcb
	(version 20260206)
	(generator "pcbnew")
	(generator_version "10.0")
	(general
		(thickness 1.6)
		(legacy_teardrops no)
	)
	(paper "A4")
	(title_block
		(title "03242023_DA0F0TMBIJ0_F0T_Motherboard_J_brd_V01_OCP.brd")
		(comment 1 "Grand Teton / footprint 2856 of 6105 (J2), pads 275-291 of 291")
	)
	(layers
		(0 "F.Cu" signal "TOP")
		(4 "In1.Cu" signal "GND")
		(6 "In2.Cu" signal "IN1")
		(8 "In3.Cu" signal "GND1")
		(10 "In4.Cu" signal "IN2")
		(12 "In5.Cu" signal "GND2")
		(14 "In6.Cu" signal "IN3")
		(16 "In7.Cu" signal "GND3")
		(18 "In8.Cu" signal "VCC")
		(20 "In9.Cu" signal "VCC1")
		(22 "In10.Cu" signal "GND4")
		(24 "In11.Cu" signal "IN4")
		(26 "In12.Cu" signal "GND5")
		(28 "In13.Cu" signal "IN5")
		(30 "In14.Cu" signal "GND6")
		(32 "In15.Cu" signal "IN6")
		(34 "In16.Cu" signal "GND7")
		(2 "B.Cu" signal "BOTTOM")
		(9 "F.Adhes" user "F.Adhesive")
		(11 "B.Adhes" user "B.Adhesive")
		(13 "F.Paste" user "Package Geometry/Pastemask Top")
		(15 "B.Paste" user "Package Geometry/Pastemask Bottom")
		(5 "F.SilkS" user "Ref Des/Silkscreen Top")
		(7 "B.SilkS" user "Ref Des/Silkscreen Bottom")
		(1 "F.Mask" user "Board Geometry/Soldermask Top")
		(3 "B.Mask" user "Board Geometry/Soldermask Bottom")
		(17 "Dwgs.User" user "User.Drawings")
		(19 "Cmts.User" user "User.Comments")
		(21 "Eco1.User" user "User.Eco1")
		(23 "Eco2.User" user "User.Eco2")
		(25 "Edge.Cuts" user "Board Geometry/Outline")
		(27 "Margin" user)
		(31 "F.CrtYd" user "Package Geometry/Place Bound Top")
		(29 "B.CrtYd" user "Package Geometry/Place Bound Bottom")
		(35 "F.Fab" user "Ref Des/Assembly Top")
		(33 "B.Fab" user "Ref Des/Assembly Bottom")
	)
	(footprint ""
		(layer "F.Cu")
		(at 310.937148 -258.091686)
		(property "Reference" "J2"
			(at -3.683 -81.702148 0)
			(unlocked yes)
			(layer "F.SilkS")
			(effects
				(font
					(size 0.7874 0.5842)
					(thickness 0.1524)
				)
				(justify left)
			)
		)
		(property "Value" ""
			(at 0 0 0)
			(layer "F.Fab")
			(effects
				(font
					(size 1.27 1.27)
				)
			)
		)
		(duplicate_pad_numbers_are_jumpers no)
		(pad "275" smd rect
			(at 2.050034 52.274978 270)
			(size 0.519938 1.4986)
			(layers "F.Cu" "F.Mask" "F.Paste")
			(net "GND")
		)
		(pad "276" smd rect
			(at 2.050034 53.125116 270)
			(size 0.519938 1.4986)
			(layers "F.Cu" "F.Mask" "F.Paste")
			(net "M_A_CPU0_SB_DQ<23>")
		)
		(pad "277" smd rect
			(at 2.050034 53.975 270)
			(size 0.519938 1.4986)
			(layers "F.Cu" "F.Mask" "F.Paste")
			(net "GND")
		)
		(pad "278" smd rect
			(at 2.050034 54.824884 270)
			(size 0.519938 1.4986)
			(layers "F.Cu" "F.Mask" "F.Paste")
			(net "M_A_CPU0_SB_DQ<26>")
		)
		(pad "279" smd rect
			(at 2.050034 55.675022 270)
			(size 0.519938 1.4986)
			(layers "F.Cu" "F.Mask" "F.Paste")
			(net "GND")
		)
		(pad "280" smd rect
			(at 2.050034 56.524906 270)
			(size 0.519938 1.4986)
			(layers "F.Cu" "F.Mask" "F.Paste")
			(net "M_A_CPU0_SB_DQ<27>")
		)
		(pad "281" smd rect
			(at 2.050034 57.375044 270)
			(size 0.519938 1.4986)
			(layers "F.Cu" "F.Mask" "F.Paste")
			(net "GND")
		)
		(pad "282" smd rect
			(at 2.050034 58.224928 270)
			(size 0.519938 1.4986)
			(layers "F.Cu" "F.Mask" "F.Paste")
			(net "M_A_CPU0_SB_DQS_DN<8>")
		)
		(pad "283" smd rect
			(at 2.050034 59.075066 270)
			(size 0.519938 1.4986)
			(layers "F.Cu" "F.Mask" "F.Paste")
			(net "M_A_CPU0_SB_DQS_DP<8>")
		)
		(pad "284" smd rect
			(at 2.050034 59.92495 270)
			(size 0.519938 1.4986)
			(layers "F.Cu" "F.Mask" "F.Paste")
			(net "GND")
		)
		(pad "285" smd rect
			(at 2.050034 60.775088 270)
			(size 0.519938 1.4986)
			(layers "F.Cu" "F.Mask" "F.Paste")
			(net "M_A_CPU0_SB_DQ<30>")
		)
		(pad "286" smd rect
			(at 2.050034 61.624972 270)
			(size 0.519938 1.4986)
			(layers "F.Cu" "F.Mask" "F.Paste")
			(net "GND")
		)
		(pad "287" smd rect
			(at 2.050034 62.47511 270)
			(size 0.519938 1.4986)
			(layers "F.Cu" "F.Mask" "F.Paste")
			(net "M_A_CPU0_SB_DQ<31>")
		)
		(pad "288" smd rect
			(at 2.050034 63.324994 270)
			(size 0.519938 1.4986)
			(layers "F.Cu" "F.Mask" "F.Paste")
			(net "GND")
		)
		(pad "G1" thru_hole oval
			(at 0 -68.97497)
			(size 2.8194 1.5748)
			(drill oval 2.4384 1.1938)
			(layers "*.Cu" "*.Mask")
			(remove_unused_layers no)
			(net "GND")
			(clearance 0.127)
			(thermal_gap 0.127)
		)
		(pad "G2" thru_hole oval
			(at 0 3.875024)
			(size 2.8194 1.5748)
			(drill oval 2.4384 1.1938)
			(layers "*.Cu" "*.Mask")
			(remove_unused_layers no)
			(net "GND")
			(clearance 0.127)
			(thermal_gap 0.127)
		)
		(pad "G3" thru_hole oval
			(at 0 68.97497)
			(size 2.8194 1.5748)
			(drill oval 2.4384 1.1938)
			(layers "*.Cu" "*.Mask")
			(remove_unused_layers no)
			(net "GND")
			(clearance 0.127)
			(thermal_gap 0.127)
		)
	)
)
